(kicad_pcb
	(version 20260206)
	(generator "pcbnew")
	(generator_version "10.0")
	(general
		(thickness 1.6)
		(legacy_teardrops no)
	)
	(paper "A4")
	(title_block
		(title "03242023_DA0F0TMBIJ0_F0T_Motherboard_J_brd_V01_OCP.brd")
		(comment 1 "Grand Teton / footprints 54-59 of 6105")
	)
	(layers
		(0 "F.Cu" signal "TOP")
		(4 "In1.Cu" signal "GND")
		(6 "In2.Cu" signal "IN1")
		(8 "In3.Cu" signal "GND1")
		(10 "In4.Cu" signal "IN2")
		(12 "In5.Cu" signal "GND2")
		(14 "In6.Cu" signal "IN3")
		(16 "In7.Cu" signal "GND3")
		(18 "In8.Cu" signal "VCC")
		(20 "In9.Cu" signal "VCC1")
		(22 "In10.Cu" signal "GND4")
		(24 "In11.Cu" signal "IN4")
		(26 "In12.Cu" signal "GND5")
		(28 "In13.Cu" signal "IN5")
		(30 "In14.Cu" signal "GND6")
		(32 "In15.Cu" signal "IN6")
		(34 "In16.Cu" signal "GND7")
		(2 "B.Cu" signal "BOTTOM")
		(9 "F.Adhes" user "F.Adhesive")
		(11 "B.Adhes" user "B.Adhesive")
		(13 "F.Paste" user "Package Geometry/Pastemask Top")
		(15 "B.Paste" user "Package Geometry/Pastemask Bottom")
		(5 "F.SilkS" user "Ref Des/Silkscreen Top")
		(7 "B.SilkS" user "Ref Des/Silkscreen Bottom")
		(1 "F.Mask" user "Board Geometry/Soldermask Top")
		(3 "B.Mask" user "Board Geometry/Soldermask Bottom")
		(17 "Dwgs.User" user "User.Drawings")
		(19 "Cmts.User" user "User.Comments")
		(21 "Eco1.User" user "User.Eco1")
		(23 "Eco2.User" user "User.Eco2")
		(25 "Edge.Cuts" user "Board Geometry/Outline")
		(27 "Margin" user)
		(31 "F.CrtYd" user "Package Geometry/Place Bound Top")
		(29 "B.CrtYd" user "Package Geometry/Place Bound Bottom")
		(35 "F.Fab" user "Ref Des/Assembly Top")
		(33 "B.Fab" user "Ref Des/Assembly Bottom")
	)
	(footprint ""
		(layer "F.Cu")
		(at 176.58588 -133.695948 -90)
		(property "Reference" "R4259"
			(at 0 0 270)
			(layer "F.SilkS")
			(hide yes)
			(effects
				(font
					(size 1.27 1.27)
				)
			)
		)
		(property "Value" ""
			(at 0 0 270)
			(layer "F.Fab")
			(effects
				(font
					(size 1.27 1.27)
				)
			)
		)
		(duplicate_pad_numbers_are_jumpers no)
		(fp_line
			(start -0.7874 0.4064)
			(end -0.7874 -0.4064)
			(stroke
				(width 0.1524)
				(type default)
			)
			(layer "F.SilkS")
		)
		(fp_line
			(start 0.7874 0.4064)
			(end -0.7874 0.4064)
			(stroke
				(width 0.1524)
				(type default)
			)
			(layer "F.SilkS")
		)
		(fp_line
			(start -0.7874 -0.4064)
			(end 0.7874 -0.4064)
			(stroke
				(width 0.1524)
				(type default)
			)
			(layer "F.SilkS")
		)
		(fp_line
			(start 0.7874 -0.4064)
			(end 0.7874 0.4064)
			(stroke
				(width 0.1524)
				(type default)
			)
			(layer "F.SilkS")
		)
		(fp_line
			(start -0.67945 0.3048)
			(end -0.67945 -0.305054)
			(stroke
				(width 0.1)
				(type default)
			)
			(layer "F.Fab")
		)
		(fp_line
			(start -0.12065 0.3048)
			(end -0.67945 0.3048)
			(stroke
				(width 0.1)
				(type default)
			)
			(layer "F.Fab")
		)
		(fp_line
			(start 0.120396 0.3048)
			(end 0.120396 0.2794)
			(stroke
				(width 0.1)
				(type default)
			)
			(layer "F.Fab")
		)
		(fp_line
			(start 0.67945 0.3048)
			(end 0.120396 0.3048)
			(stroke
				(width 0.1)
				(type default)
			)
			(layer "F.Fab")
		)
		(fp_line
			(start -0.12065 0.2794)
			(end -0.12065 0.3048)
			(stroke
				(width 0.1)
				(type default)
			)
			(layer "F.Fab")
		)
		(fp_line
			(start 0.120396 0.2794)
			(end -0.12065 0.2794)
			(stroke
				(width 0.1)
				(type default)
			)
			(layer "F.Fab")
		)
		(fp_line
			(start -0.12065 -0.2794)
			(end 0.12065 -0.2794)
			(stroke
				(width 0.1)
				(type default)
			)
			(layer "F.Fab")
		)
		(fp_line
			(start 0.12065 -0.2794)
			(end 0.12065 -0.3048)
			(stroke
				(width 0.1)
				(type default)
			)
			(layer "F.Fab")
		)
		(fp_line
			(start 0.12065 -0.3048)
			(end 0.67945 -0.3048)
			(stroke
				(width 0.1)
				(type default)
			)
			(layer "F.Fab")
		)
		(fp_line
			(start 0.67945 -0.3048)
			(end 0.67945 0.3048)
			(stroke
				(width 0.1)
				(type default)
			)
			(layer "F.Fab")
		)
		(fp_line
			(start -0.67945 -0.305054)
			(end -0.12065 -0.305054)
			(stroke
				(width 0.1)
				(type default)
			)
			(layer "F.Fab")
		)
		(fp_line
			(start -0.12065 -0.305054)
			(end -0.12065 -0.2794)
			(stroke
				(width 0.1)
				(type default)
			)
			(layer "F.Fab")
		)
		(pad "1" smd circle
			(at -0.40005 0 270)
			(size 0 0)
			(layers "F.Cu" "F.Mask" "F.Paste")
			(net "FM_THERMAL_ALERT_N")
		)
		(pad "2" smd circle
			(at 0.40005 0 270)
			(size 0 0)
			(layers "F.Cu" "F.Mask" "F.Paste")
			(net "FM_THERMAL_ALERT_R_N")
		)
	)
	(footprint ""
		(layer "F.Cu")
		(at 368.005868 -357.11638 90)
		(property "Reference" "PR1337"
			(at 0 0 90)
			(layer "F.SilkS")
			(hide yes)
			(effects
				(font
					(size 1.27 1.27)
				)
			)
		)
		(property "Value" ""
			(at 0 0 90)
			(layer "F.Fab")
			(effects
				(font
					(size 1.27 1.27)
				)
			)
		)
		(duplicate_pad_numbers_are_jumpers no)
		(fp_line
			(start 0.7874 -0.4064)
			(end 0.7874 0.4064)
			(stroke
				(width 0.1524)
				(type default)
			)
			(layer "F.SilkS")
		)
		(fp_line
			(start -0.7874 -0.4064)
			(end 0.7874 -0.4064)
			(stroke
				(width 0.1524)
				(type default)
			)
			(layer "F.SilkS")
		)
		(fp_line
			(start 0.7874 0.4064)
			(end -0.7874 0.4064)
			(stroke
				(width 0.1524)
				(type default)
			)
			(layer "F.SilkS")
		)
		(fp_line
			(start -0.7874 0.4064)
			(end -0.7874 -0.4064)
			(stroke
				(width 0.1524)
				(type default)
			)
			(layer "F.SilkS")
		)
		(fp_line
			(start -0.12065 -0.305054)
			(end -0.12065 -0.2794)
			(stroke
				(width 0.1)
				(type default)
			)
			(layer "F.Fab")
		)
		(fp_line
			(start -0.67945 -0.305054)
			(end -0.12065 -0.305054)
			(stroke
				(width 0.1)
				(type default)
			)
			(layer "F.Fab")
		)
		(fp_line
			(start 0.67945 -0.3048)
			(end 0.67945 0.3048)
			(stroke
				(width 0.1)
				(type default)
			)
			(layer "F.Fab")
		)
		(fp_line
			(start 0.12065 -0.3048)
			(end 0.67945 -0.3048)
			(stroke
				(width 0.1)
				(type default)
			)
			(layer "F.Fab")
		)
		(fp_line
			(start 0.12065 -0.2794)
			(end 0.12065 -0.3048)
			(stroke
				(width 0.1)
				(type default)
			)
			(layer "F.Fab")
		)
		(fp_line
			(start -0.12065 -0.2794)
			(end 0.12065 -0.2794)
			(stroke
				(width 0.1)
				(type default)
			)
			(layer "F.Fab")
		)
		(fp_line
			(start 0.120396 0.2794)
			(end -0.12065 0.2794)
			(stroke
				(width 0.1)
				(type default)
			)
			(layer "F.Fab")
		)
		(fp_line
			(start -0.12065 0.2794)
			(end -0.12065 0.3048)
			(stroke
				(width 0.1)
				(type default)
			)
			(layer "F.Fab")
		)
		(fp_line
			(start 0.67945 0.3048)
			(end 0.120396 0.3048)
			(stroke
				(width 0.1)
				(type default)
			)
			(layer "F.Fab")
		)
		(fp_line
			(start 0.120396 0.3048)
			(end 0.120396 0.2794)
			(stroke
				(width 0.1)
				(type default)
			)
			(layer "F.Fab")
		)
		(fp_line
			(start -0.12065 0.3048)
			(end -0.67945 0.3048)
			(stroke
				(width 0.1)
				(type default)
			)
			(layer "F.Fab")
		)
		(fp_line
			(start -0.67945 0.3048)
			(end -0.67945 -0.305054)
			(stroke
				(width 0.1)
				(type default)
			)
			(layer "F.Fab")
		)
		(pad "1" smd circle
			(at -0.40005 0 90)
			(size 0 0)
			(layers "F.Cu" "F.Mask" "F.Paste")
			(net "PVPP_HBM_CPU0_FB")
		)
		(pad "2" smd circle
			(at 0.40005 0 90)
			(size 0 0)
			(layers "F.Cu" "F.Mask" "F.Paste")
			(net "SH_PVPP_HBM_CPU0_P")
		)
	)
	(footprint ""
		(layer "F.Cu")
		(at 120.0658 -343.906348 90)
		(property "Reference" "PC585"
			(at 0 0 90)
			(layer "F.SilkS")
			(hide yes)
			(effects
				(font
					(size 1.27 1.27)
				)
			)
		)
		(property "Value" ""
			(at 0 0 90)
			(layer "F.Fab")
			(effects
				(font
					(size 1.27 1.27)
				)
			)
		)
		(duplicate_pad_numbers_are_jumpers no)
		(fp_line
			(start -3.400044 1.249934)
			(end 3.400044 1.249934)
			(stroke
				(width 0.1524)
				(type default)
			)
			(layer "F.SilkS")
		)
		(fp_circle
			(center 0 1.249934)
			(end 0 4.649978)
			(stroke
				(width 0.1524)
				(type default)
			)
			(fill no)
			(layer "F.SilkS")
		)
		(fp_poly
			(pts
				(arc
					(start -3.400044 1.249934)
					(mid 0 4.649978)
					(end 3.400044 1.249934)
				)
			)
			(stroke
				(width 0)
				(type default)
			)
			(fill yes)
			(layer "F.SilkS")
		)
		(fp_circle
			(center 0 1.249934)
			(end 0 4.649978)
			(stroke
				(width 0.1)
				(type default)
			)
			(fill no)
			(layer "F.Fab")
		)
		(pad "1" thru_hole rect
			(at 0 0 90)
			(size 1.524 1.524)
			(drill 1.016)
			(layers "*.Cu" "*.Mask")
			(remove_unused_layers no)
			(net "SW_P12V_PVCCIN_CPU1_FLT")
			(clearance 0)
			(padstack
				(mode front_inner_back)
				(layer "Inner"
					(shape circle)
					(size 1.524 1.524)
					(clearance 0)
				)
				(layer "B.Cu"
					(shape rect)
					(size 1.524 1.524)
					(clearance 0)
				)
			)
		)
		(pad "2" thru_hole circle
			(at 0 2.500122 90)
			(size 1.524 1.524)
			(drill 1.016)
			(layers "*.Cu" "*.Mask")
			(remove_unused_layers no)
			(net "GND")
			(clearance 0)
		)
	)
	(footprint ""
		(layer "F.Cu")
		(at 335.209134 -18.79727 -90)
		(property "Reference" "R1748"
			(at 0 0 270)
			(layer "F.SilkS")
			(hide yes)
			(effects
				(font
					(size 1.27 1.27)
				)
			)
		)
		(property "Value" ""
			(at 0 0 270)
			(layer "F.Fab")
			(effects
				(font
					(size 1.27 1.27)
				)
			)
		)
		(duplicate_pad_numbers_are_jumpers no)
		(fp_line
			(start -0.7874 0.4064)
			(end -0.7874 -0.4064)
			(stroke
				(width 0.1524)
				(type default)
			)
			(layer "F.SilkS")
		)
		(fp_line
			(start 0.7874 0.4064)
			(end -0.7874 0.4064)
			(stroke
				(width 0.1524)
				(type default)
			)
			(layer "F.SilkS")
		)
		(fp_line
			(start -0.7874 -0.4064)
			(end 0.7874 -0.4064)
			(stroke
				(width 0.1524)
				(type default)
			)
			(layer "F.SilkS")
		)
		(fp_line
			(start 0.7874 -0.4064)
			(end 0.7874 0.4064)
			(stroke
				(width 0.1524)
				(type default)
			)
			(layer "F.SilkS")
		)
		(fp_line
			(start -0.67945 0.3048)
			(end -0.67945 -0.305054)
			(stroke
				(width 0.1)
				(type default)
			)
			(layer "F.Fab")
		)
		(fp_line
			(start -0.12065 0.3048)
			(end -0.67945 0.3048)
			(stroke
				(width 0.1)
				(type default)
			)
			(layer "F.Fab")
		)
		(fp_line
			(start 0.120396 0.3048)
			(end 0.120396 0.2794)
			(stroke
				(width 0.1)
				(type default)
			)
			(layer "F.Fab")
		)
		(fp_line
			(start 0.67945 0.3048)
			(end 0.120396 0.3048)
			(stroke
				(width 0.1)
				(type default)
			)
			(layer "F.Fab")
		)
		(fp_line
			(start -0.12065 0.2794)
			(end -0.12065 0.3048)
			(stroke
				(width 0.1)
				(type default)
			)
			(layer "F.Fab")
		)
		(fp_line
			(start 0.120396 0.2794)
			(end -0.12065 0.2794)
			(stroke
				(width 0.1)
				(type default)
			)
			(layer "F.Fab")
		)
		(fp_line
			(start -0.12065 -0.2794)
			(end 0.12065 -0.2794)
			(stroke
				(width 0.1)
				(type default)
			)
			(layer "F.Fab")
		)
		(fp_line
			(start 0.12065 -0.2794)
			(end 0.12065 -0.3048)
			(stroke
				(width 0.1)
				(type default)
			)
			(layer "F.Fab")
		)
		(fp_line
			(start 0.12065 -0.3048)
			(end 0.67945 -0.3048)
			(stroke
				(width 0.1)
				(type default)
			)
			(layer "F.Fab")
		)
		(fp_line
			(start 0.67945 -0.3048)
			(end 0.67945 0.3048)
			(stroke
				(width 0.1)
				(type default)
			)
			(layer "F.Fab")
		)
		(fp_line
			(start -0.67945 -0.305054)
			(end -0.12065 -0.305054)
			(stroke
				(width 0.1)
				(type default)
			)
			(layer "F.Fab")
		)
		(fp_line
			(start -0.12065 -0.305054)
			(end -0.12065 -0.2794)
			(stroke
				(width 0.1)
				(type default)
			)
			(layer "F.Fab")
		)
		(pad "1" smd circle
			(at -0.40005 0 270)
			(size 0 0)
			(layers "F.Cu" "F.Mask" "F.Paste")
			(net "FM_ESPI_PLD_EN")
		)
		(pad "2" smd circle
			(at 0.40005 0 270)
			(size 0 0)
			(layers "F.Cu" "F.Mask" "F.Paste")
			(net "FM_ESPI_PLD_R_EN_BUF")
		)
	)
	(footprint ""
		(layer "F.Cu")
		(at 68.64096 -61.158628 -90)
		(property "Reference" "R3631"
			(at 0 0 270)
			(layer "F.SilkS")
			(hide yes)
			(effects
				(font
					(size 1.27 1.27)
				)
			)
		)
		(property "Value" ""
			(at 0 0 270)
			(layer "F.Fab")
			(effects
				(font
					(size 1.27 1.27)
				)
			)
		)
		(duplicate_pad_numbers_are_jumpers no)
		(fp_line
			(start -0.7874 0.4064)
			(end -0.7874 -0.4064)
			(stroke
				(width 0.1524)
				(type default)
			)
			(layer "F.SilkS")
		)
		(fp_line
			(start 0.7874 0.4064)
			(end -0.7874 0.4064)
			(stroke
				(width 0.1524)
				(type default)
			)
			(layer "F.SilkS")
		)
		(fp_line
			(start -0.7874 -0.4064)
			(end 0.7874 -0.4064)
			(stroke
				(width 0.1524)
				(type default)
			)
			(layer "F.SilkS")
		)
		(fp_line
			(start 0.7874 -0.4064)
			(end 0.7874 0.4064)
			(stroke
				(width 0.1524)
				(type default)
			)
			(layer "F.SilkS")
		)
		(fp_line
			(start -0.67945 0.3048)
			(end -0.67945 -0.305054)
			(stroke
				(width 0.1)
				(type default)
			)
			(layer "F.Fab")
		)
		(fp_line
			(start -0.12065 0.3048)
			(end -0.67945 0.3048)
			(stroke
				(width 0.1)
				(type default)
			)
			(layer "F.Fab")
		)
		(fp_line
			(start 0.120396 0.3048)
			(end 0.120396 0.2794)
			(stroke
				(width 0.1)
				(type default)
			)
			(layer "F.Fab")
		)
		(fp_line
			(start 0.67945 0.3048)
			(end 0.120396 0.3048)
			(stroke
				(width 0.1)
				(type default)
			)
			(layer "F.Fab")
		)
		(fp_line
			(start -0.12065 0.2794)
			(end -0.12065 0.3048)
			(stroke
				(width 0.1)
				(type default)
			)
			(layer "F.Fab")
		)
		(fp_line
			(start 0.120396 0.2794)
			(end -0.12065 0.2794)
			(stroke
				(width 0.1)
				(type default)
			)
			(layer "F.Fab")
		)
		(fp_line
			(start -0.12065 -0.2794)
			(end 0.12065 -0.2794)
			(stroke
				(width 0.1)
				(type default)
			)
			(layer "F.Fab")
		)
		(fp_line
			(start 0.12065 -0.2794)
			(end 0.12065 -0.3048)
			(stroke
				(width 0.1)
				(type default)
			)
			(layer "F.Fab")
		)
		(fp_line
			(start 0.12065 -0.3048)
			(end 0.67945 -0.3048)
			(stroke
				(width 0.1)
				(type default)
			)
			(layer "F.Fab")
		)
		(fp_line
			(start 0.67945 -0.3048)
			(end 0.67945 0.3048)
			(stroke
				(width 0.1)
				(type default)
			)
			(layer "F.Fab")
		)
		(fp_line
			(start -0.67945 -0.305054)
			(end -0.12065 -0.305054)
			(stroke
				(width 0.1)
				(type default)
			)
			(layer "F.Fab")
		)
		(fp_line
			(start -0.12065 -0.305054)
			(end -0.12065 -0.2794)
			(stroke
				(width 0.1)
				(type default)
			)
			(layer "F.Fab")
		)
		(pad "1" smd circle
			(at -0.40005 0 270)
			(size 0 0)
			(layers "F.Cu" "F.Mask" "F.Paste")
			(net "HP_LVC3_OCP_V3_2_EN")
		)
		(pad "2" smd circle
			(at 0.40005 0 270)
			(size 0 0)
			(layers "F.Cu" "F.Mask" "F.Paste")
			(net "P3V3_OCP_EN_2")
		)
	)
	(footprint ""
		(layer "F.Cu")
		(at 9.908032 -92.687648 90)
		(property "Reference" "R3654"
			(at 0 0 90)
			(layer "F.SilkS")
			(hide yes)
			(effects
				(font
					(size 1.27 1.27)
				)
			)
		)
		(property "Value" ""
			(at 0 0 90)
			(layer "F.Fab")
			(effects
				(font
					(size 1.27 1.27)
				)
			)
		)
		(duplicate_pad_numbers_are_jumpers no)
		(fp_line
			(start 0.7874 -0.4064)
			(end 0.7874 0.4064)
			(stroke
				(width 0.1524)
				(type default)
			)
			(layer "F.SilkS")
		)
		(fp_line
			(start -0.7874 -0.4064)
			(end 0.7874 -0.4064)
			(stroke
				(width 0.1524)
				(type default)
			)
			(layer "F.SilkS")
		)
		(fp_line
			(start 0.7874 0.4064)
			(end -0.7874 0.4064)
			(stroke
				(width 0.1524)
				(type default)
			)
			(layer "F.SilkS")
		)
		(fp_line
			(start -0.7874 0.4064)
			(end -0.7874 -0.4064)
			(stroke
				(width 0.1524)
				(type default)
			)
			(layer "F.SilkS")
		)
		(fp_line
			(start -0.12065 -0.305054)
			(end -0.12065 -0.2794)
			(stroke
				(width 0.1)
				(type default)
			)
			(layer "F.Fab")
		)
		(fp_line
			(start -0.67945 -0.305054)
			(end -0.12065 -0.305054)
			(stroke
				(width 0.1)
				(type default)
			)
			(layer "F.Fab")
		)
		(fp_line
			(start 0.67945 -0.3048)
			(end 0.67945 0.3048)
			(stroke
				(width 0.1)
				(type default)
			)
			(layer "F.Fab")
		)
		(fp_line
			(start 0.12065 -0.3048)
			(end 0.67945 -0.3048)
			(stroke
				(width 0.1)
				(type default)
			)
			(layer "F.Fab")
		)
		(fp_line
			(start 0.12065 -0.2794)
			(end 0.12065 -0.3048)
			(stroke
				(width 0.1)
				(type default)
			)
			(layer "F.Fab")
		)
		(fp_line
			(start -0.12065 -0.2794)
			(end 0.12065 -0.2794)
			(stroke
				(width 0.1)
				(type default)
			)
			(layer "F.Fab")
		)
		(fp_line
			(start 0.120396 0.2794)
			(end -0.12065 0.2794)
			(stroke
				(width 0.1)
				(type default)
			)
			(layer "F.Fab")
		)
		(fp_line
			(start -0.12065 0.2794)
			(end -0.12065 0.3048)
			(stroke
				(width 0.1)
				(type default)
			)
			(layer "F.Fab")
		)
		(fp_line
			(start 0.67945 0.3048)
			(end 0.120396 0.3048)
			(stroke
				(width 0.1)
				(type default)
			)
			(layer "F.Fab")
		)
		(fp_line
			(start 0.120396 0.3048)
			(end 0.120396 0.2794)
			(stroke
				(width 0.1)
				(type default)
			)
			(layer "F.Fab")
		)
		(fp_line
			(start -0.12065 0.3048)
			(end -0.67945 0.3048)
			(stroke
				(width 0.1)
				(type default)
			)
			(layer "F.Fab")
		)
		(fp_line
			(start -0.67945 0.3048)
			(end -0.67945 -0.305054)
			(stroke
				(width 0.1)
				(type default)
			)
			(layer "F.Fab")
		)
		(pad "1" smd circle
			(at -0.40005 0 90)
			(size 0 0)
			(layers "F.Cu" "F.Mask" "F.Paste")
			(net "RST_USB_HUB_N")
		)
		(pad "2" smd circle
			(at 0.40005 0 90)
			(size 0 0)
			(layers "F.Cu" "F.Mask" "F.Paste")
			(net "RST_USB_HUB_R_N")
		)
	)
)
